# Bryce Canyon_Rear_Drive_Plane_Board_Stackup.xlsx — PCB Test Plan_HVM(90+) (pcb-stackup)
|  | Board vendor give feedback of quantity in yellow columns based on the AQL table or description. |  |  |  |  |  |  |  |  |  |  |  |  |  |  |
|  | Wiwynn PM give feedback in blue columns |  |  |  |  |  |  |  |  |  |  |  |  |  |  |
| Person to be informed : PCB vendor, EE, SI, PM, PSM, Buyer, SQM |  |  |  |  |  |  |  |  |  |  |  |  |  |  |  |
| Simple flow : SI (test requirements) -> PM/AM (Total PCBS demand) -> Buyer -> Board Vendor (yellow column feedback) -> Buyer -> Person to be informed (Check and Track) |  |  |  |  |  |  |  |  |  |  |  |  |  |  |  |
| PO(purchase order) : If there are many POs for this PCB, 1st sample quantity is based on 1st PO, 2nd sample quantity is based on 2nd PO. |  |  |  |  |  |  |  |  |  |  |  |  |  |  |  |
| Project Name | PCB name | PCB# (1XXXX-XX) | Product Stage | Batch# | PCB Vendor | Production  Lot size | PCBs Demand | Delta-L Coupon (PCB Vendor) | Delta-L Coupon (3rd Party Lab) | Impedance Coupon (PCB Vendor) | In-board trace correlation (PCB Vendor) | X-section Analysis (PCB Vendor) | IST (3rd Party Lab) | IPC-6012D (3rd Party Lab) | Note |
| Bryce Canyon | FDPB | 16315-1 | HVM(90+ days) | N/A |  |  | TBD | Yes | No | Yes | No | No | No | No | Need Test? (Yes, No) |
| Tracking Code On Both Of Coupon And PCB |  |  |  |  |  |  |  | N/A |  | N/A |  |  |  |  |  |
| Test Item Acceptance Criteria |  |  |  |  |  |  |  | c = 0 |  | c = 0 |  |  |  |  |  |
| Test Item Sampling Quantity |  |  |  |  |  |  |  | 5 pcs/production lot/quarter, with max total of 30 pcs |  | Mil-STD 105E single sampling plan, AQL 0.65, level 2 |  |  |  |  |  |
| Test Time(working days) |  |  |  |  |  |  |  |  |  |  |  |  |  |  |  |
| Test Item Shipping Quantity |  |  |  |  |  |  |  |  |  |  |  |  |  |  |  |
| Shipping Address |  |  |  |  |  |  |  |  |  |  |  |  |  |  |  |
| Receiver Name |  |  |  |  |  |  |  |  |  |  |  |  |  |  |  |
| Receiver Phone# |  |  |  |  |  |  |  |  |  |  |  |  |  |  |  |
| Project Name | PCB name | PCB# (1XXXX-XX) | Product Stage | Batch# | PCB Vendor | Production  Lot size | PCBs Demand | Delta-L Coupon (PCB Vendor) | Delta-L Coupon (3rd Party Lab) | Impedance Coupon (PCB Vendor) | In-board trace correlation (PCB Vendor) | X-section Analysis (PCB Vendor) | IST (3rd Party Lab) | IPC-6012D (3rd Party Lab) | Note |
| Bryce Canyon | SCC | 16316-1 | HVM(90+ days) | N/A |  |  | TBD | No | No | Yes | No | No | No | No | Need Test? (Yes, No) |
| Tracking Code On Both Of Coupon And PCB |  |  |  |  |  |  |  |  |  | N/A |  |  |  |  |  |
| Test Item Acceptance Criteria |  |  |  |  |  |  |  |  |  | c = 0 |  |  |  |  |  |
| Test Item Sampling Quantity |  |  |  |  |  |  |  |  |  | Mil-STD 105E single sampling plan, AQL 0.65, level 2 |  |  |  |  |  |
| Test Time (working days) |  |  |  |  |  |  |  |  |  |  |  |  |  |  |  |
| Test Item Shipping Quantity |  |  |  |  |  |  |  |  |  |  |  |  |  |  |  |
| Shipping Address |  |  |  |  |  |  |  |  |  |  |  |  |  |  |  |
| Receiver Name |  |  |  |  |  |  |  |  |  |  |  |  |  |  |  |
| Receiver Phone# |  |  |  |  |  |  |  |  |  |  |  |  |  |  |  |
| Project Name | PCB name | PCB# (1XXXX-XX) | Product Stage | Batch# | PCB Vendor | Production  Lot size | PCBs Demand | Delta-L Coupon (PCB Vendor) | Delta-L Coupon (3rd Party Lab) | Impedance Coupon (PCB Vendor) | In-board trace correlation (PCB Vendor) | X-section Analysis (PCB Vendor) | IST (3rd Party Lab) | IPC-6012D (3rd Party Lab) | Note |
| Bryce Canyon | RDPB | 16317-1 | HVM(90+ days) | N/A |  |  | TBD | Yes | No | Yes | No | No | No | No | Need Test? (Yes, No) |
| Tracking Code On Both Of Coupon And PCB |  |  |  |  |  |  |  | N/A |  | N/A |  |  |  |  |  |
| Test Item Acceptance Criteria |  |  |  |  |  |  |  | c = 0 |  | c = 0 |  |  |  |  |  |
| Test Item Sampling Quantity |  |  |  |  |  |  |  | 5 pcs/production lot/quarter, with max total of 30 pcs |  | Mil-STD 105E single sampling plan, AQL 0.65, level 2 |  |  |  |  |  |
| Test Time (working days) |  |  |  |  |  |  |  |  |  |  |  |  |  |  |  |
| Test Item Shipping Quantity |  |  |  |  |  |  |  |  |  |  |  |  |  |  |  |
| Shipping Address |  |  |  |  |  |  |  |  |  |  |  |  |  |  |  |
| Receiver Name |  |  |  |  |  |  |  |  |  |  |  |  |  |  |  |
| Receiver Phone# |  |  |  |  |  |  |  |  |  |  |  |  |  |  |  |
| Project Name | PCB name | PCB# (1XXXX-XX) | Product Stage | Batch# | PCB Vendor | Production  Lot size | PCBs Demand | Delta-L Coupon (PCB Vendor) | Delta-L Coupon (3rd Party Lab) | Impedance Coupon (PCB Vendor) | In-board trace correlation (PCB Vendor) | X-section Analysis (PCB Vendor) | IST (3rd Party Lab) | IPC-6012D (3rd Party Lab) | Note |
| Bryce Canyon | IOM IOC | 16318-1 | HVM(90+ days) | N/A |  |  | TBD | No | No | Yes | No | No | No | No | Need Test? (Yes, No) |
| Tracking Code On Both Of Coupon And PCB |  |  |  |  |  |  |  |  |  | N/A |  |  |  |  |  |
| Test Item Acceptance Criteria |  |  |  |  |  |  |  |  |  | c = 0 |  |  |  |  |  |
| Test Item Sampling Quantity |  |  |  |  |  |  |  |  |  | Mil-STD 105E single sampling plan, AQL 0.65, level 2 |  |  |  |  |  |
| Test Time (working days) |  |  |  |  |  |  |  |  |  |  |  |  |  |  |  |
| Test Item Shipping Quantity |  |  |  |  |  |  |  |  |  |  |  |  |  |  |  |
| Shipping Address |  |  |  |  |  |  |  |  |  |  |  |  |  |  |  |
| Receiver Name |  |  |  |  |  |  |  |  |  |  |  |  |  |  |  |
| Receiver Phone# |  |  |  |  |  |  |  |  |  |  |  |  |  |  |  |
| Project Name | PCB name | PCB# (1XXXX-XX) | Product Stage | Batch# | PCB Vendor | Production  Lot size | PCBs Demand | Delta-L Coupon (PCB Vendor) | Delta-L Coupon (3rd Party Lab) | Impedance Coupon (PCB Vendor) | In-board trace correlation (PCB Vendor) | X-section Analysis (PCB Vendor) | IST (3rd Party Lab) | IPC-6012D (3rd Party Lab) | Note |
| Bryce Canyon | IOM M2 | 16342-1 | HVM(90+ days) | N/A |  |  | TBD | No | No | Yes | No | No | No | No | Need Test? (Yes, No) |
| Tracking Code On Both Of Coupon And PCB |  |  |  |  |  |  |  |  |  | N/A |  |  |  |  |  |
| Test Item Acceptance Criteria |  |  |  |  |  |  |  |  |  | c = 0 |  |  |  |  |  |
| Test Item Sampling Quantity |  |  |  |  |  |  |  |  |  | Mil-STD 105E single sampling plan, AQL 0.65, level 2 |  |  |  |  |  |
| Test Time (working days) |  |  |  |  |  |  |  |  |  |  |  |  |  |  |  |
| Test Item Shipping Quantity |  |  |  |  |  |  |  |  |  |  |  |  |  |  |  |
| Shipping Address |  |  |  |  |  |  |  |  |  |  |  |  |  |  |  |
| Receiver Name |  |  |  |  |  |  |  |  |  |  |  |  |  |  |  |
| Receiver Phone# |  |  |  |  |  |  |  |  |  |  |  |  |  |  |  |
